# S9S_MB_2U (Grand Teton) — schematic netlist excerpt (pin names and nets, part order shuffled) for the footprints in the layout excerpt that follows; sources: Cadence DE-HDL packaged netlist, KiCad conversion of 03242023_DA0F0TMBIJ0_F0T_Motherboard_J_brd_V01_OCP.brd

PR4010  Q_RES  120K 1% CHIP  pkg 0402LF  page 242 : A = P12V_AUX ; B = P12V_SCM_OV_FB
C4562  Q_CAP  1UF 25V 10% EMPTY  pkg C0402  page 306 : A = U369_VDD ; B = GND

(kicad_pcb
	(version 20260206)
	(generator "pcbnew")
	(generator_version "10.0")
	(general
		(thickness 1.6)
		(legacy_teardrops no)
	)
	(paper "A4")
	(title_block
		(title "03242023_DA0F0TMBIJ0_F0T_Motherboard_J_brd_V01_OCP.brd")
		(comment 1 "Grand Teton / footprints 777-778 of 6105")
	)
	(layers
		(0 "F.Cu" signal "TOP")
		(4 "In1.Cu" signal "GND")
		(6 "In2.Cu" signal "IN1")
		(8 "In3.Cu" signal "GND1")
		(10 "In4.Cu" signal "IN2")
		(12 "In5.Cu" signal "GND2")
		(14 "In6.Cu" signal "IN3")
		(16 "In7.Cu" signal "GND3")
		(18 "In8.Cu" signal "VCC")
		(20 "In9.Cu" signal "VCC1")
		(22 "In10.Cu" signal "GND4")
		(24 "In11.Cu" signal "IN4")
		(26 "In12.Cu" signal "GND5")
		(28 "In13.Cu" signal "IN5")
		(30 "In14.Cu" signal "GND6")
		(32 "In15.Cu" signal "IN6")
		(34 "In16.Cu" signal "GND7")
		(2 "B.Cu" signal "BOTTOM")
		(9 "F.Adhes" user "F.Adhesive")
		(11 "B.Adhes" user "B.Adhesive")
		(13 "F.Paste" user "Package Geometry/Pastemask Top")
		(15 "B.Paste" user "Package Geometry/Pastemask Bottom")
		(5 "F.SilkS" user "Ref Des/Silkscreen Top")
		(7 "B.SilkS" user "Ref Des/Silkscreen Bottom")
		(1 "F.Mask" user "Board Geometry/Soldermask Top")
		(3 "B.Mask" user "Board Geometry/Soldermask Bottom")
		(17 "Dwgs.User" user "User.Drawings")
		(19 "Cmts.User" user "User.Comments")
		(21 "Eco1.User" user "User.Eco1")
		(23 "Eco2.User" user "User.Eco2")
		(25 "Edge.Cuts" user "Board Geometry/Outline")
		(27 "Margin" user)
		(31 "F.CrtYd" user "Package Geometry/Place Bound Top")
		(29 "B.CrtYd" user "Package Geometry/Place Bound Bottom")
		(35 "F.Fab" user "Ref Des/Assembly Top")
		(33 "B.Fab" user "Ref Des/Assembly Bottom")
	)
	(footprint ""
		(layer "F.Cu")
		(at 279.40762 -426.68698)
		(property "Reference" "C4562"
			(at 0 0 0)
			(layer "F.SilkS")
			(hide yes)
			(effects
				(font
					(size 1.27 1.27)
				)
			)
		)
		(property "Value" ""
			(at 0 0 0)
			(layer "F.Fab")
			(effects
				(font
					(size 1.27 1.27)
				)
			)
		)
		(duplicate_pad_numbers_are_jumpers no)
		(fp_line
			(start -0.7874 -0.4064)
			(end 0.7874 -0.4064)
			(stroke
				(width 0.1524)
				(type default)
			)
			(layer "F.SilkS")
		)
		(fp_line
			(start -0.7874 0.4064)
			(end -0.7874 -0.4064)
			(stroke
				(width 0.1524)
				(type default)
			)
			(layer "F.SilkS")
		)
		(fp_line
			(start 0.7874 -0.4064)
			(end 0.7874 0.4064)
			(stroke
				(width 0.1524)
				(type default)
			)
			(layer "F.SilkS")
		)
		(fp_line
			(start 0.7874 0.4064)
			(end -0.7874 0.4064)
			(stroke
				(width 0.1524)
				(type default)
			)
			(layer "F.SilkS")
		)
		(fp_line
			(start -0.67945 -0.305054)
			(end -0.12065 -0.305054)
			(stroke
				(width 0.1)
				(type default)
			)
			(layer "F.Fab")
		)
		(fp_line
			(start -0.67945 0.3048)
			(end -0.67945 -0.305054)
			(stroke
				(width 0.1)
				(type default)
			)
			(layer "F.Fab")
		)
		(fp_line
			(start -0.12065 -0.305054)
			(end -0.12065 -0.2794)
			(stroke
				(width 0.1)
				(type default)
			)
			(layer "F.Fab")
		)
		(fp_line
			(start -0.12065 -0.2794)
			(end 0.12065 -0.2794)
			(stroke
				(width 0.1)
				(type default)
			)
			(layer "F.Fab")
		)
		(fp_line
			(start -0.12065 0.2794)
			(end -0.12065 0.3048)
			(stroke
				(width 0.1)
				(type default)
			)
			(layer "F.Fab")
		)
		(fp_line
			(start -0.12065 0.3048)
			(end -0.67945 0.3048)
			(stroke
				(width 0.1)
				(type default)
			)
			(layer "F.Fab")
		)
		(fp_line
			(start 0.120396 0.2794)
			(end -0.12065 0.2794)
			(stroke
				(width 0.1)
				(type default)
			)
			(layer "F.Fab")
		)
		(fp_line
			(start 0.120396 0.3048)
			(end 0.120396 0.2794)
			(stroke
				(width 0.1)
				(type default)
			)
			(layer "F.Fab")
		)
		(fp_line
			(start 0.12065 -0.3048)
			(end 0.67945 -0.3048)
			(stroke
				(width 0.1)
				(type default)
			)
			(layer "F.Fab")
		)
		(fp_line
			(start 0.12065 -0.2794)
			(end 0.12065 -0.3048)
			(stroke
				(width 0.1)
				(type default)
			)
			(layer "F.Fab")
		)
		(fp_line
			(start 0.67945 -0.3048)
			(end 0.67945 0.3048)
			(stroke
				(width 0.1)
				(type default)
			)
			(layer "F.Fab")
		)
		(fp_line
			(start 0.67945 0.3048)
			(end 0.120396 0.3048)
			(stroke
				(width 0.1)
				(type default)
			)
			(layer "F.Fab")
		)
		(pad "1" smd circle
			(at -0.40005 0)
			(size 0 0)
			(layers "F.Cu" "F.Mask" "F.Paste")
			(net "U369_VDD")
		)
		(pad "2" smd circle
			(at 0.40005 0)
			(size 0 0)
			(layers "F.Cu" "F.Mask" "F.Paste")
			(net "GND")
		)
	)
	(footprint ""
		(layer "F.Cu")
		(at 172.878242 -28.03779 90)
		(property "Reference" "PR4010"
			(at 0 0 90)
			(layer "F.SilkS")
			(hide yes)
			(effects
				(font
					(size 1.27 1.27)
				)
			)
		)
		(property "Value" ""
			(at 0 0 90)
			(layer "F.Fab")
			(effects
				(font
					(size 1.27 1.27)
				)
			)
		)
		(duplicate_pad_numbers_are_jumpers no)
		(fp_line
			(start 0.7874 -0.4064)
			(end 0.7874 0.4064)
			(stroke
				(width 0.1524)
				(type default)
			)
			(layer "F.SilkS")
		)
		(fp_line
			(start -0.7874 -0.4064)
			(end 0.7874 -0.4064)
			(stroke
				(width 0.1524)
				(type default)
			)
			(layer "F.SilkS")
		)
		(fp_line
			(start 0.7874 0.4064)
			(end -0.7874 0.4064)
			(stroke
				(width 0.1524)
				(type default)
			)
			(layer "F.SilkS")
		)
		(fp_line
			(start -0.7874 0.4064)
			(end -0.7874 -0.4064)
			(stroke
				(width 0.1524)
				(type default)
			)
			(layer "F.SilkS")
		)
		(fp_line
			(start -0.12065 -0.305054)
			(end -0.12065 -0.2794)
			(stroke
				(width 0.1)
				(type default)
			)
			(layer "F.Fab")
		)
		(fp_line
			(start -0.67945 -0.305054)
			(end -0.12065 -0.305054)
			(stroke
				(width 0.1)
				(type default)
			)
			(layer "F.Fab")
		)
		(fp_line
			(start 0.67945 -0.3048)
			(end 0.67945 0.3048)
			(stroke
				(width 0.1)
				(type default)
			)
			(layer "F.Fab")
		)
		(fp_line
			(start 0.12065 -0.3048)
			(end 0.67945 -0.3048)
			(stroke
				(width 0.1)
				(type default)
			)
			(layer "F.Fab")
		)
		(fp_line
			(start 0.12065 -0.2794)
			(end 0.12065 -0.3048)
			(stroke
				(width 0.1)
				(type default)
			)
			(layer "F.Fab")
		)
		(fp_line
			(start -0.12065 -0.2794)
			(end 0.12065 -0.2794)
			(stroke
				(width 0.1)
				(type default)
			)
			(layer "F.Fab")
		)
		(fp_line
			(start 0.120396 0.2794)
			(end -0.12065 0.2794)
			(stroke
				(width 0.1)
				(type default)
			)
			(layer "F.Fab")
		)
		(fp_line
			(start -0.12065 0.2794)
			(end -0.12065 0.3048)
			(stroke
				(width 0.1)
				(type default)
			)
			(layer "F.Fab")
		)
		(fp_line
			(start 0.67945 0.3048)
			(end 0.120396 0.3048)
			(stroke
				(width 0.1)
				(type default)
			)
			(layer "F.Fab")
		)
		(fp_line
			(start 0.120396 0.3048)
			(end 0.120396 0.2794)
			(stroke
				(width 0.1)
				(type default)
			)
			(layer "F.Fab")
		)
		(fp_line
			(start -0.12065 0.3048)
			(end -0.67945 0.3048)
			(stroke
				(width 0.1)
				(type default)
			)
			(layer "F.Fab")
		)
		(fp_line
			(start -0.67945 0.3048)
			(end -0.67945 -0.305054)
			(stroke
				(width 0.1)
				(type default)
			)
			(layer "F.Fab")
		)
		(pad "1" smd circle
			(at -0.40005 0 90)
			(size 0 0)
			(layers "F.Cu" "F.Mask" "F.Paste")
			(net "P12V_AUX")
		)
		(pad "2" smd circle
			(at 0.40005 0 90)
			(size 0 0)
			(layers "F.Cu" "F.Mask" "F.Paste")
			(net "P12V_SCM_OV_FB")
		)
	)
)
